FILE_TYPE = CONNECTIVITY;
{Allegro Design Entry HDL 17.2-2016 S081 (4005846) 1/11/2022}
"PAGE_NUMBER" = 197;
0"NC";
1"P3V3_AUX\g";
2"P3V3_AUX_CLK_GEN_VDD_CK440\g";
3"P3V3_AUX_CLK_GEN_VDDA25M_CK440\g";
4"P3V3_AUX_CLK_GEN_VDDXTAL_CK440\g";
5"P3V3_AUX_CLK_GEN_VDDA100M_CK440\g";
6"P3V3_AUX_CLK_GEN_VDDPT_CK440\g";
7"P3V3_AUX\g";
8"P3V3_AUX_CLK_GEN_VDDMXCK_CK440\g";
9"P3V3_AUX\g";
10"GND\g";
11"GND\g";
12"GND\g";
13"GND\g";
14"GND\g";
15"XTAL_CLK_GEN1_25M_X2";
16"XTAL_CLK_GEN1_25M_X1_R";
17"CLK_CK440_SMB_ADDR1";
18"SMB_HOST_CLK_3V3AUX_SDA";
19"SMB_HOST_CLK_3V3AUX_SCL";
20"PU_CK440_SHFT_LD_N";
21"CLK_CK440_SMB_ADDR0";
22"FM_CLK_CK440_SS_EN";
23"FM_CLK_GEN1_OE0_N";
24"CK440Q_OE_1";
25"CK440Q_OE_4";
26"NC_CLK_CK440_100M6_DN";
27"XTAL_CLK_GEN1_25M_X1"CDS_PHYS_NET_NAME"FM_PLD_CLK_25M_EN";
28"PU_CLK_PFT_LOST_N";
29"FM_CK440Q_DEV_25M_EN";
30"FM_PLD_CLK_25M_EN"CDS_PHYS_NET_NAME"FM_PLD_CLK_25M_EN";
31"NC_CLK_CK440_MXCK8_DN";
32"TP_CLK_CK440_PFT_OUT_DP";
33"TP_CLK_CK440_PFT_OUT_DN";
34"NC_CLK_CK440_MXCK7_DP";
35"NC_CLK_CK440_MXCK6_DN";
36"NC_CLK_CK440_MXCK5_DP";
37"NC_CLK_CK440_MXCK5_DN";
38"NC_CLK_CK440_MXCK4_DN";
39"NC_CLK_CK440_MXCK4_DP";
40"NC_CLK_CK440_MXCK3_DN";
41"NC_CLK_CK440_MXCK3_DP";
42"CLK_100M_CK440_PCH_EXTCLK_R_DN";
43"NC_CLK_CK440_MXCK6_DP";
44"NC_CLK_CK440_MXCK7_DN";
45"NC_CLK_CK440_MXCK8_DP";
46"CLK_100M_CK440_PCH_EXTCLK_R_DP";
47"NC_CLK_CK440_MXCK0_DN";
48"NC_CLK_CK440_MXCK0_DP";
49"CLK_25M_CK440_ISCLK_REF_DN";
50"NC_CLK_CK440_MXCK1_DP";
51"NC_CLK_CK440_MXCK1_DN";
52"CLK_25M_CK440_ISCLK_REF_DP";
53"CLK_25M_CK440_CPU1_DN";
54"CLK_25M_CK440_CPU1_DP";
55"CLK_25M_CK440_CPU0_DN";
56"CLK_25M_CK440_CPU0_DP";
57"NC_CLK_CK440_100M6_DP";
58"NC_CLK_CK440_100M5_DN";
59"NC_CLK_CK440_100M5_DP";
60"NC_CLK_CK440_100M4_DN";
61"FM_CK440_MXCK_25M_100M";
62"FM_PLD_CLKS_DEV_EN";
63"FM_PLD_CLKS_DEV_EN";
64"TP_CLK_PFT_IN_DN";
65"CK440Q_OE_6";
66"CK440Q_OE_3";
67"CK440Q_OE_5";
68"TP_CLK_PFT_IN_DP";
69"CK440Q_OE_2";
70"TP_CK440_SBI_DATA_OUT";
71"CLK_CK440_SMB_ADDR1";
72"CLK_CK440_SMB_ADDR0";
73"FM_CK440_MXCK_25M_100M";
74"PD_CK440_SBI_CLK";
75"NC_CLK_CK440_100M4_DP";
76"NC_CLK_CK440_100M3_DN";
77"NC_CLK_CK440_100M3_DP";
78"NC_CLK_CK440_100M2_DN";
79"NC_CLK_CK440_100M2_DP";
80"NC_CLK_CK440_100M1_DN";
81"NC_CLK_CK440_100M1_DP";
82"CLK_100M_DB2000_DN";
83"NC_CK440_B39";
84"NC_CK440_B41";
85"NC_CK440_B44";
86"PD_CK440_SBI_DATA_IN";
87"FM_CK440Q_DEV_25M_EN";
88"FM_CLK_CK440_SS_EN";
89"PU_CK440_SHFT_LD_N";
90"PD_CK440_SBI_CLK";
91"FM_CLK_GEN1_OE0_N";
92"PD_CK440_SBI_DATA_IN";
93"CLK_100M_DB2000_DP";
94"NC_CK440_B37";
95"NC_CK440_B36";
96"NC_CK440_B34";
97"NC_CK440_B33";
98"NC_CK440_B31";
99"NC_CK440_B30";
100"NC_CK440_B28";
101"NC_CK440_B26";
102"NC_CK440_B25";
103"NC_CK440_B24";
104"NC_CK440_A15";
105"NC_CK440_B2";
106"NC_CK440_B3";
107"NC_CK440_B5";
108"NC_CK440_B7";
109"NC_CK440_B13";
110"NC_CK440_B16";
111"NC_CK440_B18";
112"NC_CK440_B20";
113"NC_CK440_B22";
%"UNIVERSAL_POWER"
"1","(-1725,8675)","0","logical_power","I157";
;
HDL_POWER"P3V3_AUX_CLK_GEN_VDDA100M_CK440"
CDS_LIB"logical_power";
"A"5;
%"UNIVERSAL_POWER"
"1","(-2175,8800)","0","logical_power","I158";
;
HDL_POWER"P3V3_AUX_CLK_GEN_VDDA25M_CK440"
CDS_LIB"logical_power";
"A"3;
%"UNIVERSAL_POWER"
"1","(-1325,8550)","0","logical_power","I159";
;
HDL_POWER"P3V3_AUX_CLK_GEN_VDD_CK440"
CDS_LIB"logical_power";
"A"2;
%"UNIVERSAL_POWER"
"1","(-2625,8950)","0","logical_power","I160";
;
HDL_POWER"P3V3_AUX_CLK_GEN_VDDMXCK_CK440"
CDS_LIB"logical_power";
"A"8;
%"UNIVERSAL_POWER"
"1","(-3050,9100)","0","logical_power","I161";
;
HDL_POWER"P3V3_AUX_CLK_GEN_VDDPT_CK440"
CDS_LIB"logical_power";
"A"6;
%"UNIVERSAL_POWER"
"1","(-3475,9250)","0","logical_power","I162";
;
HDL_POWER"P3V3_AUX_CLK_GEN_VDDXTAL_CK440"
CDS_LIB"logical_power";
"A"4;
%"9SQ440NQQI8"
"1","(-300,7325)","0","pure_quanta","I180";
;
PART_NUMBER"AJ004400000"
PART_TYPE"SMLF"
MATERIAL"IC"
VALUE"9SQ440NQQI8"
$LOCATION"U13"
NEEDS_NO_SIZE"TRUE"
CDS_LIB"pure_quanta"
CDS_LMAN_SYM_OUTLINE"-650,1300,650,-1300"
CDS_LOCATION"U13"
$SEC"1"
CDS_SEC"1";
"VDD100M_B23"
$PN"B23"2;
"VDD100M_B21"
$PN"B21"2;
"VDDMXCK_B40"
$PN"B40"8;
"VDDMXCK_B35"
$PN"B35"8;
"VDDMXCK_B32"
$PN"B32"8;
"VDDMXCK_B29"
$PN"B29"8;
"XOUT"
$PN"B11"15;
"XIN_CLKIN"
$PN"A13"27;
"VDDXTAL"
$PN"A12"4;
"VDDPT"
$PN"B6"6;
"VDDA100M"
$PN"B17"5;
"VDDA25M"
$PN"B1"3;
"SS_EN_TRI"
$PN"A16"22;
"SMB_ADR0_TRI"
$PN"A11"21;
"SMBDATTA"
$PN"B8"18;
"SCLK"
$PN"A10"19;
"SBI_OUT"
$PN"A53"70;
"SBI_IN"
$PN"B43"86;
"PWRGD||PWRDN#"
$PN"A17"63;
"PFT_OUT"
$PN"A6"32;
"PFT_OUT# \B"
$PN"A7"33;
"PFT_LOST# \B"
$PN"B4"28;
"PFT_IN"
$PN"A8"68;
"PFT_IN# \B"
$PN"A9"64;
"OE6# \B"
$PN"B14"65;
"OE0# \B"
$PN"B27"23;
"NVGND"
$PN"B12"11;
"MXCK_SEL_100M# \B"
$PN"B38"61;
"MXCK8"
$PN"A36"45;
"MXCK8# \B"
$PN"A35"31;
"MXCK7"
$PN"A38"34;
"MXCK7# \B"
$PN"A37"44;
"MXCK6"
$PN"A40"43;
"MXCK6# \B"
$PN"A39"35;
"MXCK5"
$PN"A42"36;
"MXCK5# \B"
$PN"A41"37;
"MXCK4"
$PN"A44"39;
"MXCK4# \B"
$PN"A43"38;
"MXCK3"
$PN"A46"41;
"MXCK3# \B"
$PN"A45"40;
"MXCK2"
$PN"A48"46;
"MXCK2# \B"
$PN"A47"42;
"MXCK1"
$PN"A50"50;
"MXCK1# \B"
$PN"A49"51;
"MXCK0"
$PN"A52"48;
"MXCK0# \B"
$PN"A51"47;
"GNDS"
$PN"B10"11;
"100M6"
$PN"A19"57;
"100M6# \B"
$PN"A18"26;
"100M5"
$PN"A21"59;
"100M5# \B"
$PN"A20"58;
"100M4"
$PN"A23"75;
"100M4# \B"
$PN"A22"60;
"100M3"
$PN"A25"77;
"100M3# \B"
$PN"A24"76;
"100M2"
$PN"A28"79;
"100M2# \B"
$PN"A27"78;
"100M1"
$PN"A32"81;
"100M1# \B"
$PN"A31"80;
"100M0"
$PN"A34"93;
"100M0# \B"
$PN"A33"82;
"25MPG"
$PN"A1"29;
"25M2"
$PN"A56"52;
"25M2# \B"
$PN"A55"49;
"25M1"
$PN"A3"54;
"25M0"
$PN"A5"56;
"25M0# \B"
$PN"A4"55;
"OE5# \B"
$PN"B15"67;
"OE1# \B"
$PN"A30"24;
"OE4# \B"
$PN"B19"25;
"OE3# \B"
$PN"A26"66;
"OE2# \B"
$PN"A29"69;
"SHFT_LD# \B"
$PN"B42"20;
"SBI_CLK"
$PN"A54"74;
"SMB_ADR1_TRI"
$PN"B9"17;
"GNDXTAL"
$PN"A14"11;
"EPAD"
$PN"C1"11;
"25M1# \B"
$PN"A2"53;
%"Q_RES"
"1","(-2325,6125)","0","pure_quanta","I252";
;
PART_NUMBER"CS00002JB13"
WATTAGE"1/16W"
VALUE"0"
MATERIAL"CHIP"
TOLERANCE"5%"
PACK_TYPE"0402LF"
$LOCATION"R1680"
CDS_LIB"pure_quanta"
CDS_LOCATION"R1680"
$SEC"1"
CDS_SEC"1";
"B"
$PN"2"29;
"A"
$PN"1"30;
%"Q_RES"
"2","(-3150,10725)","0","pure_quanta","I265";
;
PART_NUMBER"CS31002FB08"
WATTAGE"1/16W"
TOLERANCE"1%"
VALUE"10K"
MATERIAL"EMPTY"
PACK_TYPE"0402LF"
$LOCATION"R1483"
CDS_LIB"pure_quanta"
CDS_LOCATION"R1483"
$SEC"1"
CDS_SEC"1";
"A"
$PN"1"7;
"B"
$PN"2"87;
%"Q_RES"
"2","(-3625,10725)","0","pure_quanta","I267";
;
PART_NUMBER"CS24752FB03"
VALUE"4.75K"
MATERIAL"CHIP"
WATTAGE"1/16W"
TOLERANCE"1%"
PACK_TYPE"0402LF"
$LOCATION"R1471"
CDS_LIB"pure_quanta"
CDS_LOCATION"R1471"
$SEC"1"
CDS_SEC"1";
"A"
$PN"1"7;
"B"
$PN"2"88;
%"Q_RES"
"2","(-3150,9800)","0","pure_quanta","I268";
;
PART_NUMBER"CS21002FB06"
TOLERANCE"1%"
MATERIAL"EMPTY"
WATTAGE"1/16W"
PACK_TYPE"0402LF"
VALUE"1K"
$LOCATION"R1484"
CDS_LIB"pure_quanta"
CDS_LOCATION"R1484"
$SEC"1"
CDS_SEC"1";
"A"
$PN"1"87;
"B"
$PN"2"10;
%"Q_RES"
"2","(-3375,9800)","0","pure_quanta","I269";
;
PART_NUMBER"CS21002FB06"
VALUE"1K"
TOLERANCE"1%"
WATTAGE"1/16W"
MATERIAL"CHIP"
PACK_TYPE"0402LF"
$LOCATION"R1527"
CDS_LIB"pure_quanta"
CDS_LOCATION"R1527"
$SEC"1"
CDS_SEC"1";
"A"
$PN"1"91;
"B"
$PN"2"10;
%"Q_RES"
"2","(-3625,9800)","0","pure_quanta","I270";
;
PART_NUMBER"CS24752FB03"
TOLERANCE"1%"
PACK_TYPE"0402LF"
WATTAGE"1/16W"
MATERIAL"CHIP"
VALUE"4.75K"
$LOCATION"R1502"
CDS_LIB"pure_quanta"
CDS_LOCATION"R1502"
$SEC"1"
CDS_SEC"1";
"A"
$PN"1"88;
"B"
$PN"2"10;
%"Q_RES"
"2","(-3875,9800)","0","pure_quanta","I271";
;
PART_NUMBER"CS24752FB03"
PACK_TYPE"0402LF"
VALUE"4.75K"
TOLERANCE"1%"
WATTAGE"1/16W"
MATERIAL"CHIP"
$LOCATION"R1500"
CDS_LIB"pure_quanta"
CDS_LOCATION"R1500"
$SEC"1"
CDS_SEC"1";
"A"
$PN"1"92;
"B"
$PN"2"10;
%"Q_RES"
"2","(-4400,10725)","0","pure_quanta","I272";
;
PART_NUMBER"CS31002FB08"
MATERIAL"EMPTY"
WATTAGE"1/16W"
PACK_TYPE"0402LF"
TOLERANCE"1%"
VALUE"10K"
$LOCATION"R1305"
CDS_LIB"pure_quanta"
CDS_LOCATION"R1305"
$SEC"1"
CDS_SEC"1";
"A"
$PN"1"7;
"B"
$PN"2"62;
%"Q_RES"
"2","(-4675,10725)","0","pure_quanta","I273";
;
PART_NUMBER"CS31002FB08"
WATTAGE"1/16W"
MATERIAL"EMPTY"
TOLERANCE"1%"
PACK_TYPE"0402LF"
VALUE"10K"
$LOCATION"R1204"
CDS_LIB"pure_quanta"
CDS_LOCATION"R1204"
$SEC"1"
CDS_SEC"1";
"A"
$PN"1"7;
"B"
$PN"2"89;
%"Q_RES"
"2","(-4125,9800)","0","pure_quanta","I274";
;
PART_NUMBER"CS21002FB06"
VALUE"1K"
TOLERANCE"1%"
MATERIAL"CHIP"
WATTAGE"1/16W"
PACK_TYPE"0402LF"
$LOCATION"R1462"
CDS_LIB"pure_quanta"
CDS_LOCATION"R1462"
$SEC"1"
CDS_SEC"1";
"A"
$PN"1"90;
"B"
$PN"2"10;
%"Q_RES"
"2","(-4400,9800)","0","pure_quanta","I275";
;
PART_NUMBER"CS21002FB06"
VALUE"1K"
TOLERANCE"1%"
MATERIAL"EMPTY"
WATTAGE"1/16W"
PACK_TYPE"0402LF"
$LOCATION"R1390"
CDS_LIB"pure_quanta"
CDS_LOCATION"R1390"
$SEC"1"
CDS_SEC"1";
"A"
$PN"1"62;
"B"
$PN"2"10;
%"Q_RES"
"2","(-4675,9800)","0","pure_quanta","I276";
;
PART_NUMBER"CS21002FB06"
TOLERANCE"1%"
VALUE"1K"
WATTAGE"1/16W"
MATERIAL"CHIP"
PACK_TYPE"0402LF"
$LOCATION"R1267"
CDS_LIB"pure_quanta"
CDS_LOCATION"R1267"
$SEC"1"
CDS_SEC"1";
"A"
$PN"1"89;
"B"
$PN"2"10;
%"Q_RES"
"2","(-5100,10725)","0","pure_quanta","I277";
;
PART_NUMBER"CS24752FB03"
TOLERANCE"1%"
WATTAGE"1/16W"
VALUE"4.75K"
MATERIAL"EMPTY"
PACK_TYPE"0402LF"
$LOCATION"R1194"
CDS_LIB"pure_quanta"
CDS_LOCATION"R1194"
$SEC"1"
CDS_SEC"1";
"A"
$PN"1"7;
"B"
$PN"2"73;
%"Q_RES"
"2","(-5350,10725)","0","pure_quanta","I278";
;
PART_NUMBER"CS24752FB03"
TOLERANCE"1%"
MATERIAL"EMPTY"
PACK_TYPE"0402LF"
VALUE"4.75K"
WATTAGE"1/16W"
$LOCATION"R912"
CDS_LIB"pure_quanta"
CDS_LOCATION"R912"
$SEC"1"
CDS_SEC"1";
"A"
$PN"1"7;
"B"
$PN"2"72;
%"UNIVERSAL_POWER"
"1","(-5625,11125)","0","logical_power","I279";
;
HDL_POWER"P3V3_AUX"
CDS_LIB"logical_power";
"A"7;
%"Q_RES"
"2","(-5625,10725)","0","pure_quanta","I280";
;
PART_NUMBER"CS24752FB03"
TOLERANCE"1%"
PACK_TYPE"0402LF"
VALUE"4.75K"
MATERIAL"EMPTY"
WATTAGE"1/16W"
$LOCATION"R2481"
CDS_LIB"pure_quanta"
CDS_LOCATION"R2481"
$SEC"1"
CDS_SEC"1";
"A"
$PN"1"7;
"B"
$PN"2"71;
%"Q_RES"
"2","(-5100,9800)","0","pure_quanta","I281";
;
PART_NUMBER"CS24752FB03"
PACK_TYPE"0402LF"
VALUE"4.75K"
WATTAGE"1/16W"
TOLERANCE"1%"
MATERIAL"CHIP"
$LOCATION"R1196"
CDS_LIB"pure_quanta"
CDS_LOCATION"R1196"
$SEC"1"
CDS_SEC"1";
"A"
$PN"1"73;
"B"
$PN"2"10;
%"Q_RES"
"2","(-5350,9800)","0","pure_quanta","I282";
;
PART_NUMBER"CS24752FB03"
VALUE"4.75K"
MATERIAL"CHIP"
TOLERANCE"1%"
PACK_TYPE"0402LF"
WATTAGE"1/16W"
$LOCATION"R953"
CDS_LIB"pure_quanta"
CDS_LOCATION"R953"
$SEC"1"
CDS_SEC"1";
"A"
$PN"1"72;
"B"
$PN"2"10;
%"Q_RES"
"2","(-5625,9800)","0","pure_quanta","I283";
;
PART_NUMBER"CS24752FB03"
PACK_TYPE"0402LF"
MATERIAL"CHIP"
TOLERANCE"1%"
WATTAGE"1/16W"
VALUE"4.75K"
$LOCATION"R734"
CDS_LIB"pure_quanta"
CDS_LOCATION"R734"
$SEC"1"
CDS_SEC"1";
"A"
$PN"1"71;
"B"
$PN"2"10;
%"UNIVERSAL_GND"
"1","(-1950,5550)","0","logical_power","I285";
;
CDS_LIB"logical_power"
HDL_POWER"GND";
"A"14;
%"Q_CAP"
"1","(-1950,5775)","2","pure_quanta","I286";
;
PART_NUMBER"CH4104K1B00"
PACK_TYPE"0402"
TOLERANCE"10%"
VOLTAGE"25V"
VALUE"0.1UF"
MATERIAL"EMPTY"
$LOCATION"C1324"
CDS_LIB"pure_quanta"
CDS_LOCATION"C1324"
$SEC"1"
CDS_SEC"1";
"B"
$PN"2"14;
"A"
$PN"1"29;
%"9SQ440NQQI8"
"2","(-25,10275)","0","pure_quanta","I288";
;
PART_NUMBER"AJ004400000"
MATERIAL"IC"
VALUE"9SQ440NQQI8"
PART_TYPE"SMLF"
$LOCATION"U13"
CDS_LIB"pure_quanta"
NEEDS_NO_SIZE"TRUE"
CDS_LMAN_SYM_OUTLINE"-350,400,350,-350"
CDS_LOCATION"U13"
$SEC"2"
CDS_SEC"2";
"NC_B44"
$PN"B44"85;
"NC_B41"
$PN"B41"84;
"NC_B39"
$PN"B39"83;
"NC_B37"
$PN"B37"94;
"NC_B36"
$PN"B36"95;
"NC_B34"
$PN"B34"96;
"NC_B33"
$PN"B33"97;
"NC_B31"
$PN"B31"98;
"NC_B30"
$PN"B30"99;
"NC_B28"
$PN"B28"100;
"NC_B26"
$PN"B26"101;
"NC_B25"
$PN"B25"102;
"NC_B24"
$PN"B24"103;
"NC_A15"
$PN"A15"104;
"NC_B2"
$PN"B2"105;
"NC_B3"
$PN"B3"106;
"NC_B5"
$PN"B5"107;
"NC_B7"
$PN"B7"108;
"NC_B13"
$PN"B13"109;
"NC_B16"
$PN"B16"110;
"NC_B18"
$PN"B18"111;
"NC_B20"
$PN"B20"112;
"NC_B22"
$PN"B22"113;
%"UNIVERSAL_GND"
"1","(-4275,5125)","0","logical_power","I294";
;
HDL_POWER"GND"
CDS_LIB"logical_power";
"A"13;
%"UNIVERSAL_GND"
"1","(-5175,5125)","0","logical_power","I295";
;
HDL_POWER"GND"
CDS_LIB"logical_power";
"A"12;
%"UNIVERSAL_GND"
"1","(675,5825)","0","logical_power","I301";
;
CDS_LIB"logical_power"
HDL_POWER"GND";
"A"11;
%"UNIVERSAL_GND"
"1","(-5625,9400)","0","logical_power","I302";
;
HDL_POWER"GND"
CDS_LIB"logical_power";
"A"10;
%"Q_RES"
"2","(-4575,6750)","2","pure_quanta","I303";
;
PART_NUMBER"CS31002FB08"
TOLERANCE"1%"
WATTAGE"1/16W"
VALUE"10K"
MATERIAL"CHIP"
PACK_TYPE"0402LF"
$LOCATION"R1958"
CDS_LIB"pure_quanta"
CDS_LOCATION"R1958"
$SEC"1"
CDS_SEC"1";
"A"
$PN"1"9;
"B"
$PN"2"28;
%"UNIVERSAL_POWER"
"1","(-4575,6975)","0","logical_power","I304";
;
HDL_POWER"P3V3_AUX"
CDS_LIB"logical_power";
"A"9;
%"Q_RES"
"1","(-2650,6925)","0","pure_quanta","I378";
;
PART_NUMBER"CS31002FB08"
TOLERANCE"1%"
MATERIAL"CHIP"
VALUE"10K"
$LOCATION"R3638"
CDS_LIB"pure_quanta"
PACK_TYPE"0402LF"
WATTAGE"1/16W"
CDS_LOCATION"R3638"
$SEC"1"
CDS_SEC"1";
"B"
$PN"2"24;
"A"
$PN"1"1;
%"Q_RES"
"1","(-2650,6875)","0","pure_quanta","I379";
;
PART_NUMBER"CS31002FB08"
TOLERANCE"1%"
VALUE"10K"
MATERIAL"CHIP"
$LOCATION"R3639"
CDS_LIB"pure_quanta"
PACK_TYPE"0402LF"
WATTAGE"1/16W"
CDS_LOCATION"R3639"
$SEC"1"
CDS_SEC"1";
"B"
$PN"2"69;
"A"
$PN"1"1;
%"Q_RES"
"1","(-2650,6825)","0","pure_quanta","I380";
;
PART_NUMBER"CS31002FB08"
TOLERANCE"1%"
VALUE"10K"
MATERIAL"CHIP"
$LOCATION"R3640"
CDS_LIB"pure_quanta"
PACK_TYPE"0402LF"
WATTAGE"1/16W"
CDS_LOCATION"R3640"
$SEC"1"
CDS_SEC"1";
"B"
$PN"2"66;
"A"
$PN"1"1;
%"Q_RES"
"1","(-2650,6775)","0","pure_quanta","I381";
;
PART_NUMBER"CS31002FB08"
VALUE"10K"
TOLERANCE"1%"
MATERIAL"CHIP"
$LOCATION"R3641"
CDS_LIB"pure_quanta"
PACK_TYPE"0402LF"
WATTAGE"1/16W"
CDS_LOCATION"R3641"
$SEC"1"
CDS_SEC"1";
"B"
$PN"2"25;
"A"
$PN"1"1;
%"Q_RES"
"1","(-2650,6725)","0","pure_quanta","I382";
;
PART_NUMBER"CS31002FB08"
VALUE"10K"
MATERIAL"CHIP"
TOLERANCE"1%"
$LOCATION"R3642"
CDS_LIB"pure_quanta"
PACK_TYPE"0402LF"
WATTAGE"1/16W"
CDS_LOCATION"R3642"
$SEC"1"
CDS_SEC"1";
"B"
$PN"2"67;
"A"
$PN"1"1;
%"Q_RES"
"1","(-2650,6675)","0","pure_quanta","I383";
;
PART_NUMBER"CS31002FB08"
VALUE"10K"
MATERIAL"CHIP"
TOLERANCE"1%"
$LOCATION"R3643"
CDS_LIB"pure_quanta"
PACK_TYPE"0402LF"
WATTAGE"1/16W"
CDS_LOCATION"R3643"
$SEC"1"
CDS_SEC"1";
"B"
$PN"2"65;
"A"
$PN"1"1;
%"UNIVERSAL_POWER"
"1","(-3175,7125)","0","logical_power","I385";
;
HDL_POWER"P3V3_AUX"
CDS_LIB"logical_power";
"A"1;
%"Q_XTAL_4P_13BI_24GND"
"1","(-4725,5725)","0","pure_quanta","I391";
;
PART_NUMBER"BG6250000F0"
PART_TYPE"SMLF"
VALUE"25MHZ"
MATERIAL"MISC"
LOCATION"Y2"
CDS_LIB"pure_quanta"
CDS_LMAN_SYM_OUTLINE"-125,175,125,-175"
PIN_NAMES_ROTATE"True"
$SEC"1"
CDS_SEC"1";
"X2"
$PN"3"15;
"G2"
$PN"4"13;
"G1"
$PN"2"12;
"X1"
$PN"1"16;
%"Q_RES"
"1","(-4150,6275)","0","pure_quanta","I392";
;
PART_NUMBER"CS00002JB13"
WATTAGE"1/16W"
PACK_TYPE"0402LF"
VALUE"0"
TOLERANCE"5%"
MATERIAL"CHIP"
LOCATION"R1724"
CDS_LIB"pure_quanta"
$SEC"1"
CDS_SEC"1";
"B"
$PN"2"27;
"A"
$PN"1"16;
%"Q_CAP"
"1","(-5175,5475)","0","pure_quanta","I393";
;
PART_NUMBER"CH-8216TB09"
VALUE"8.2PF"
MATERIAL"NP0"
PACK_TYPE"C0402"
VOLTAGE"50V"
TOLERANCE"0.1P"
LOCATION"C2036"
CDS_LIB"pure_quanta"
$SEC"1"
CDS_SEC"1";
"B"
$PN"2"12;
"A"
$PN"1"16;
%"Q_CAP"
"1","(-4275,5475)","0","pure_quanta","I394";
;
PART_NUMBER"CH-8216TB09"
PACK_TYPE"C0402"
MATERIAL"NP0"
VOLTAGE"50V"
TOLERANCE"0.1P"
VALUE"8.2PF"
LOCATION"C2037"
CDS_LIB"pure_quanta"
$SEC"1"
CDS_SEC"1";
"B"
$PN"2"13;
"A"
$PN"1"15;
END.
